(kicad_pcb
	(version 20260206)
	(generator "pcbnew")
	(generator_version "10.0")
	(general
		(thickness 1.6)
		(legacy_teardrops no)
	)
	(paper "A4")
	(title_block
		(title "Wiwynn_Tioga_Pass_MB.brd")
		(comment 1 "Tioga Pass / footprints 2654-2660 of 4770")
	)
	(layers
		(0 "F.Cu" signal "TOP")
		(4 "In1.Cu" signal "L2GND")
		(6 "In2.Cu" signal "L3")
		(8 "In3.Cu" signal "L4GND")
		(10 "In4.Cu" signal "L5")
		(12 "In5.Cu" signal "L6GND")
		(14 "In6.Cu" signal "L7VCC")
		(16 "In7.Cu" signal "L8VCC")
		(18 "In8.Cu" signal "L9GND")
		(20 "In9.Cu" signal "L10")
		(22 "In10.Cu" signal "L11GND")
		(24 "In11.Cu" signal "L12")
		(26 "In12.Cu" signal "L13GND")
		(2 "B.Cu" signal "BOTTOM")
		(9 "F.Adhes" user "F.Adhesive")
		(11 "B.Adhes" user "B.Adhesive")
		(13 "F.Paste" user "Package Geometry/Pastemask Top")
		(15 "B.Paste" user "Package Geometry/Pastemask Bottom")
		(5 "F.SilkS" user "Ref Des/Silkscreen Top")
		(7 "B.SilkS" user "Ref Des/Silkscreen Bottom")
		(1 "F.Mask" user "Board Geometry/Soldermask Top")
		(3 "B.Mask" user "Board Geometry/Soldermask Bottom")
		(17 "Dwgs.User" user "User.Drawings")
		(19 "Cmts.User" user "User.Comments")
		(21 "Eco1.User" user "User.Eco1")
		(23 "Eco2.User" user "User.Eco2")
		(25 "Edge.Cuts" user "Board Geometry/Outline")
		(27 "Margin" user)
		(31 "F.CrtYd" user "Package Geometry/Place Bound Top")
		(29 "B.CrtYd" user "Package Geometry/Place Bound Bottom")
		(35 "F.Fab" user "Ref Des/Assembly Top")
		(33 "B.Fab" user "Ref Des/Assembly Bottom")
	)
	(footprint ""
		(layer "B.Cu")
		(at 436.547006 -41.648126 180)
		(property "Reference" "R25W17"
			(at 0 0 0)
			(layer "B.SilkS")
			(hide yes)
			(effects
				(font
					(size 1.27 1.27)
				)
				(justify mirror)
			)
		)
		(property "Value" "*"
			(at -0.064008 -4.108196 180)
			(unlocked yes)
			(layer "B.Fab")
			(hide yes)
			(effects
				(font
					(size 1.27 1.016)
					(thickness 0.1524)
				)
				(justify mirror)
			)
		)
		(property "Device Type" "120R2F-GP_RCL_GP-120R2F-GP,64.A"
			(at -0.064008 -5.632196 180)
			(unlocked yes)
			(layer "B.Fab")
			(hide yes)
			(effects
				(font
					(size 1.27 1.016)
					(thickness 0.1524)
				)
				(justify mirror)
			)
		)
		(duplicate_pad_numbers_are_jumpers no)
		(fp_line
			(start 0.508 -0.9398)
			(end 0.508 0.9398)
			(stroke
				(width 0.1524)
				(type default)
			)
			(layer "B.SilkS")
		)
		(fp_line
			(start -0.508 -0.9398)
			(end 0.508 -0.9398)
			(stroke
				(width 0.1524)
				(type default)
			)
			(layer "B.SilkS")
		)
		(fp_rect
			(start 0.508 0.9398)
			(end -0.508 -0.9398)
			(stroke
				(width 0)
				(type default)
			)
			(fill no)
			(layer "B.CrtYd")
		)
		(fp_rect
			(start 0.508 0.9398)
			(end -0.508 -0.9398)
			(stroke
				(width 0)
				(type default)
			)
			(fill no)
			(layer "B.Fab")
		)
		(pad "1" smd custom
			(at 0 -0.4445)
			(size 0.1397 0.1397)
			(layers "B.Cu" "B.Mask" "B.Paste")
			(net "GND")
			(options
				(clearance outline)
				(anchor circle)
			)
			(primitives
				(gr_poly
					(pts
						(arc
							(start -0.1778 0.2794)
							(mid -0.249642 0.249642)
							(end -0.2794 0.1778)
						)
						(arc
							(start -0.2794 -0.1778)
							(mid -0.249642 -0.249642)
							(end -0.1778 -0.2794)
						)
						(arc
							(start 0.1778 -0.2794)
							(mid 0.249642 -0.249642)
							(end 0.2794 -0.1778)
						)
						(arc
							(start 0.2794 0.1778)
							(mid 0.249642 0.249642)
							(end 0.1778 0.2794)
						)
					)
					(width 0)
					(fill yes)
				)
			)
		)
		(pad "2" smd custom
			(at 0 0.4445)
			(size 0.1397 0.1397)
			(layers "B.Cu" "B.Mask" "B.Paste")
			(net "BMC_M_A5")
			(options
				(clearance outline)
				(anchor circle)
			)
			(primitives
				(gr_poly
					(pts
						(arc
							(start -0.1778 0.2794)
							(mid -0.249642 0.249642)
							(end -0.2794 0.1778)
						)
						(arc
							(start -0.2794 -0.1778)
							(mid -0.249642 -0.249642)
							(end -0.1778 -0.2794)
						)
						(arc
							(start 0.1778 -0.2794)
							(mid 0.249642 -0.249642)
							(end 0.2794 -0.1778)
						)
						(arc
							(start 0.2794 0.1778)
							(mid 0.249642 0.249642)
							(end 0.1778 0.2794)
						)
					)
					(width 0)
					(fill yes)
				)
			)
		)
	)
	(footprint ""
		(layer "B.Cu")
		(at 276.000464 -149.8092 90)
		(property "Reference" "C5G72"
			(at -1.14681 0.76708 180)
			(unlocked yes)
			(layer "B.SilkS")
			(effects
				(font
					(size 0.7874 0.5842)
					(thickness 0.1524)
				)
				(justify mirror)
			)
		)
		(property "Value" ""
			(at 0 0 90)
			(layer "B.Fab")
			(effects
				(font
					(size 1.27 1.27)
				)
				(justify mirror)
			)
		)
		(duplicate_pad_numbers_are_jumpers no)
		(fp_rect
			(start -0.4953 -0.2032)
			(end 0.4953 1.6002)
			(stroke
				(width 0)
				(type default)
			)
			(fill no)
			(layer "B.CrtYd")
		)
		(fp_line
			(start 0.4953 -0.2032)
			(end -0.4953 -0.2032)
			(stroke
				(width 0.1)
				(type default)
			)
			(layer "B.Fab")
		)
		(fp_line
			(start -0.4953 -0.2032)
			(end -0.4953 1.6002)
			(stroke
				(width 0.1)
				(type default)
			)
			(layer "B.Fab")
		)
		(fp_line
			(start 0.4953 1.6002)
			(end 0.4953 -0.2032)
			(stroke
				(width 0.1)
				(type default)
			)
			(layer "B.Fab")
		)
		(fp_line
			(start -0.4953 1.6002)
			(end 0.4953 1.6002)
			(stroke
				(width 0.1)
				(type default)
			)
			(layer "B.Fab")
		)
		(pad "1" smd rect
			(at 0 0 270)
			(size 0.762 0.889)
			(layers "B.Cu" "B.Mask" "B.Paste")
			(net "PVDDQ_DEF")
		)
		(pad "2" smd rect
			(at 0 1.397 270)
			(size 0.762 0.889)
			(layers "B.Cu" "B.Mask" "B.Paste")
			(net "GND")
		)
		(zone
			(layer "B.Cu")
			(hatch none 0.5)
			(connect_pads
				(clearance 0)
			)
			(min_thickness 0.25)
			(keepout
				(tracks not_allowed)
				(vias allowed)
				(pads allowed)
				(copperpour not_allowed)
				(footprints allowed)
			)
			(placement
				(enabled no)
				(sheetname "")
			)
			(fill
				(thermal_gap 0.5)
				(thermal_bridge_width 0.5)
				(island_removal_mode 0)
			)
			(polygon
				(pts
					(xy 276.444964 -149.4282) (xy 276.952964 -149.4282) (xy 276.952964 -150.1902) (xy 276.444964 -150.1902)
				)
			)
		)
	)
	(footprint ""
		(layer "B.Cu")
		(at 341.1982 -86.5632 90)
		(property "Reference" "R3P15"
			(at 0 0 90)
			(layer "B.SilkS")
			(hide yes)
			(effects
				(font
					(size 1.27 1.27)
				)
				(justify mirror)
			)
		)
		(property "Value" ""
			(at 0 0 90)
			(layer "B.Fab")
			(effects
				(font
					(size 1.27 1.27)
				)
				(justify mirror)
			)
		)
		(duplicate_pad_numbers_are_jumpers no)
		(fp_poly
			(pts
				(xy 0.2794 -0.1016) (xy -0.2794 -0.1016) (xy -0.2794 0.9906) (xy 0.2794 0.9906)
			)
			(stroke
				(width 0)
				(type default)
			)
			(fill no)
			(layer "B.CrtYd")
		)
		(fp_line
			(start 0.2794 -0.1016)
			(end 0.2794 0.9906)
			(stroke
				(width 0.1)
				(type default)
			)
			(layer "B.Fab")
		)
		(fp_line
			(start -0.2794 -0.1016)
			(end 0.2794 -0.1016)
			(stroke
				(width 0.1)
				(type default)
			)
			(layer "B.Fab")
		)
		(fp_line
			(start 0.2794 0.9906)
			(end -0.2794 0.9906)
			(stroke
				(width 0.1)
				(type default)
			)
			(layer "B.Fab")
		)
		(fp_line
			(start -0.2794 0.9906)
			(end -0.2794 -0.1016)
			(stroke
				(width 0.1)
				(type default)
			)
			(layer "B.Fab")
		)
		(pad "1" smd rect
			(at 0 0 270)
			(size 0.508 0.508)
			(layers "B.Cu" "B.Mask" "B.Paste")
			(net "SVID_CLK0_CPU0_R")
		)
		(pad "2" smd rect
			(at 0 0.889 270)
			(size 0.508 0.508)
			(layers "B.Cu" "B.Mask" "B.Paste")
			(net "SVID_CLK_PVCCIO_CPU0")
		)
		(zone
			(layer "B.Cu")
			(hatch none 0.5)
			(connect_pads
				(clearance 0)
			)
			(min_thickness 0.25)
			(keepout
				(tracks allowed)
				(vias not_allowed)
				(pads allowed)
				(copperpour not_allowed)
				(footprints allowed)
			)
			(placement
				(enabled no)
				(sheetname "")
			)
			(fill
				(thermal_gap 0.5)
				(thermal_bridge_width 0.5)
				(island_removal_mode 0)
			)
			(polygon
				(pts
					(xy 341.4522 -86.8172) (xy 341.4522 -86.3092) (xy 341.8332 -86.3092) (xy 341.8332 -86.8172)
				)
			)
		)
		(zone
			(layer "B.Cu")
			(hatch none 0.5)
			(connect_pads
				(clearance 0)
			)
			(min_thickness 0.25)
			(keepout
				(tracks not_allowed)
				(vias allowed)
				(pads allowed)
				(copperpour not_allowed)
				(footprints allowed)
			)
			(placement
				(enabled no)
				(sheetname "")
			)
			(fill
				(thermal_gap 0.5)
				(thermal_bridge_width 0.5)
				(island_removal_mode 0)
			)
			(polygon
				(pts
					(xy 341.8332 -86.8172) (xy 341.8332 -86.3092) (xy 341.4522 -86.3092) (xy 341.4522 -86.8172)
				)
			)
		)
	)
	(footprint ""
		(layer "B.Cu")
		(at 388.502906 -164.916612 90)
		(property "Reference" "T1D18"
			(at 0 0 90)
			(layer "B.SilkS")
			(hide yes)
			(effects
				(font
					(size 1.27 1.27)
				)
				(justify mirror)
			)
		)
		(property "Value" "*"
			(at 3.4036 -4.46405 90)
			(unlocked yes)
			(layer "B.Fab")
			(hide yes)
			(effects
				(font
					(size 0.889 0.889)
					(thickness 0.1524)
				)
				(justify mirror)
			)
		)
		(property "Device Type" "TEST-PAD-12P-1-GP-U_DISCRET-GBA"
			(at 3.4036 -5.98805 90)
			(unlocked yes)
			(layer "B.Fab")
			(hide yes)
			(effects
				(font
					(size 0.889 0.889)
					(thickness 0.1524)
				)
				(justify mirror)
			)
		)
		(duplicate_pad_numbers_are_jumpers no)
		(fp_line
			(start 2.3876 -4.826)
			(end -2.3622 -4.826)
			(stroke
				(width 0.1524)
				(type default)
			)
			(layer "B.SilkS")
		)
		(fp_line
			(start -2.3622 -4.826)
			(end -2.3622 3.4798)
			(stroke
				(width 0.1524)
				(type default)
			)
			(layer "B.SilkS")
		)
		(fp_line
			(start 2.3876 3.4798)
			(end 2.3876 -4.826)
			(stroke
				(width 0.1524)
				(type default)
			)
			(layer "B.SilkS")
		)
		(fp_line
			(start -2.3622 3.4798)
			(end 2.3876 3.4798)
			(stroke
				(width 0.1524)
				(type default)
			)
			(layer "B.SilkS")
		)
		(fp_rect
			(start 2.6416 3.7338)
			(end -2.6162 -5.08)
			(stroke
				(width 0)
				(type default)
			)
			(fill no)
			(layer "B.CrtYd")
		)
		(fp_rect
			(start 2.6416 3.7338)
			(end -2.6162 -5.08)
			(stroke
				(width 0)
				(type default)
			)
			(fill no)
			(layer "B.Fab")
		)
		(pad "1" smd circle
			(at -0.496824 -1.301496 270)
			(size 0.6604 0.6604)
			(layers "B.Cu" "B.Mask" "B.Paste")
			(net "L5_85OHM_10INCH_DN")
		)
		(pad "2" smd circle
			(at 0.503936 -1.301496 270)
			(size 0.6604 0.6604)
			(layers "B.Cu" "B.Mask" "B.Paste")
			(net "L5_85OHM_10INCH_DP")
		)
		(pad "3" smd custom
			(at 0.00889 0.370078 270)
			(size 0.74295 0.74295)
			(layers "B.Cu" "B.Mask" "B.Paste")
			(net "GND")
			(options
				(clearance outline)
				(anchor circle)
			)
			(primitives
				(gr_poly
					(pts
						(xy -2.1209 -1.4859) (xy 2.1209 -1.4859) (xy 2.1209 1.4859) (xy 1.08585 1.4859) (xy 1.08585 0.4699)
						(xy -1.08585 0.4699) (xy -1.08585 1.4859) (xy -2.1209 1.4859)
					)
					(width 0)
					(fill yes)
				)
			)
		)
		(pad "4" thru_hole circle
			(at -1.266444 -3.851656 270)
			(size 1.4478 1.4478)
			(drill 1.0414)
			(layers "*.Cu" "*.Mask")
			(remove_unused_layers no)
			(net "GND")
			(clearance 0.1524)
			(thermal_gap 0.1524)
		)
		(pad "5" thru_hole circle
			(at 1.273556 -3.851656 270)
			(size 1.4478 1.4478)
			(drill 1.0414)
			(layers "*.Cu" "*.Mask")
			(remove_unused_layers no)
			(net "GND")
			(clearance 0.1524)
			(thermal_gap 0.1524)
		)
		(pad "6" thru_hole circle
			(at -1.266444 2.498344 270)
			(size 1.4478 1.4478)
			(drill 1.0414)
			(layers "*.Cu" "*.Mask")
			(remove_unused_layers no)
			(net "GND")
			(clearance 0.1524)
			(thermal_gap 0.1524)
		)
		(pad "7" thru_hole circle
			(at 1.273556 2.498344 270)
			(size 1.4478 1.4478)
			(drill 1.0414)
			(layers "*.Cu" "*.Mask")
			(remove_unused_layers no)
			(net "GND")
			(clearance 0.1524)
			(thermal_gap 0.1524)
		)
		(pad "8" thru_hole circle
			(at -1.27 -0.4572 270)
			(size 0.7112 0.7112)
			(drill 0.4064)
			(layers "*.Cu" "*.Mask")
			(remove_unused_layers no)
			(net "GND")
			(clearance 0.1016)
			(thermal_gap 0.1016)
		)
		(pad "9" thru_hole circle
			(at -1.27 0.762 270)
			(size 0.7112 0.7112)
			(drill 0.4064)
			(layers "*.Cu" "*.Mask")
			(remove_unused_layers no)
			(net "GND")
			(clearance 0.1016)
			(thermal_gap 0.1016)
		)
		(pad "10" thru_hole circle
			(at 0.0254 0.762 270)
			(size 0.7112 0.7112)
			(drill 0.4064)
			(layers "*.Cu" "*.Mask")
			(remove_unused_layers no)
			(net "GND")
			(clearance 0.1016)
			(thermal_gap 0.1016)
		)
		(pad "11" thru_hole circle
			(at 1.27 0.762 270)
			(size 0.7112 0.7112)
			(drill 0.4064)
			(layers "*.Cu" "*.Mask")
			(remove_unused_layers no)
			(net "GND")
			(clearance 0.1016)
			(thermal_gap 0.1016)
		)
		(pad "12" thru_hole circle
			(at 1.27 -0.4572 270)
			(size 0.7112 0.7112)
			(drill 0.4064)
			(layers "*.Cu" "*.Mask")
			(remove_unused_layers no)
			(net "GND")
			(clearance 0.1016)
			(thermal_gap 0.1016)
		)
	)
	(footprint ""
		(layer "B.Cu")
		(at 388.9248 -3.103372)
		(property "Reference" "U8W1"
			(at 0.14986 2.621788 0)
			(unlocked yes)
			(layer "B.SilkS")
			(effects
				(font
					(size 1.27 0.964946)
					(thickness 0.000001)
				)
				(justify left mirror)
			)
		)
		(property "Value" ""
			(at 0 0 0)
			(layer "B.Fab")
			(effects
				(font
					(size 1.27 1.27)
				)
				(justify mirror)
			)
		)
		(duplicate_pad_numbers_are_jumpers no)
		(fp_circle
			(center 0.4699 -0.8382)
			(end 0.5969 -0.8382)
			(stroke
				(width 0.254)
				(type default)
			)
			(fill no)
			(layer "B.SilkS")
		)
		(fp_poly
			(pts
				(xy -0.21463 -0.450088) (xy -1.56337 -0.450088) (xy -1.56337 1.75006) (xy -0.21463 1.75006)
			)
			(stroke
				(width 0)
				(type default)
			)
			(fill no)
			(layer "B.CrtYd")
		)
		(fp_line
			(start -1.56337 -0.450088)
			(end -1.56337 1.75006)
			(stroke
				(width 0.1)
				(type default)
			)
			(layer "B.Fab")
		)
		(fp_line
			(start -1.56337 1.75006)
			(end -0.21463 1.75006)
			(stroke
				(width 0.1)
				(type default)
			)
			(layer "B.Fab")
		)
		(fp_line
			(start -0.21463 -0.450088)
			(end -1.56337 -0.450088)
			(stroke
				(width 0.1)
				(type default)
			)
			(layer "B.Fab")
		)
		(fp_line
			(start -0.21463 1.75006)
			(end -0.21463 -0.450088)
			(stroke
				(width 0.1)
				(type default)
			)
			(layer "B.Fab")
		)
		(fp_circle
			(center 0.4699 -0.8382)
			(end 0.5969 -0.8382)
			(stroke
				(width 0.254)
				(type default)
			)
			(fill no)
			(layer "B.Fab")
		)
		(pad "1" smd rect
			(at 0 0 180)
			(size 1.016 0.381)
			(layers "B.Cu" "B.Mask" "B.Paste")
			(net "JTAG_RISER_N")
		)
		(pad "2" smd rect
			(at 0 0.649986 180)
			(size 1.016 0.381)
			(layers "B.Cu" "B.Mask" "B.Paste")
			(net "JTAG_PLD_TDO")
		)
		(pad "3" smd rect
			(at 0 1.299972 180)
			(size 1.016 0.381)
			(layers "B.Cu" "B.Mask" "B.Paste")
			(net "GND")
		)
		(pad "4" smd rect
			(at -1.778 1.299972 180)
			(size 1.016 0.381)
			(layers "B.Cu" "B.Mask" "B.Paste")
			(net "JTAG_RISER_TDI_R")
		)
		(pad "5" smd rect
			(at -1.778 0 180)
			(size 1.016 0.381)
			(layers "B.Cu" "B.Mask" "B.Paste")
			(net "P3V3_STBY")
		)
	)
	(footprint ""
		(layer "B.Cu")
		(at 384.0734 -158.26994 -90)
		(property "Reference" "CT69"
			(at 0.8382 -0.84963 270)
			(unlocked yes)
			(layer "B.SilkS")
			(effects
				(font
					(size 0.7874 0.5842)
					(thickness 0.1524)
				)
				(justify left mirror)
			)
		)
		(property "Value" ""
			(at 0 0 90)
			(layer "B.Fab")
			(effects
				(font
					(size 1.27 1.27)
				)
				(justify mirror)
			)
		)
		(duplicate_pad_numbers_are_jumpers no)
		(fp_poly
			(pts
				(xy -0.3048 -0.1016) (xy -0.3048 0.9906) (xy 0.3048 0.9906) (xy 0.3048 -0.1016)
			)
			(stroke
				(width 0)
				(type default)
			)
			(fill no)
			(layer "B.CrtYd")
		)
		(fp_line
			(start -0.3048 0.9906)
			(end -0.3048 -0.1016)
			(stroke
				(width 0.1)
				(type default)
			)
			(layer "B.Fab")
		)
		(fp_line
			(start 0.3048 0.9906)
			(end -0.3048 0.9906)
			(stroke
				(width 0.1)
				(type default)
			)
			(layer "B.Fab")
		)
		(fp_line
			(start -0.3048 -0.1016)
			(end 0.3048 -0.1016)
			(stroke
				(width 0.1)
				(type default)
			)
			(layer "B.Fab")
		)
		(fp_line
			(start 0.3048 -0.1016)
			(end 0.3048 0.9906)
			(stroke
				(width 0.1)
				(type default)
			)
			(layer "B.Fab")
		)
		(pad "1" smd rect
			(at 0 0 90)
			(size 0.508 0.508)
			(layers "B.Cu" "B.Mask" "B.Paste")
			(net "A_TSENSE_P1V05_PCH_STBY_TMON")
		)
		(pad "2" smd rect
			(at 0 0.889 90)
			(size 0.508 0.508)
			(layers "B.Cu" "B.Mask" "B.Paste")
			(net "GND")
		)
		(zone
			(layer "B.Cu")
			(hatch none 0.5)
			(connect_pads
				(clearance 0)
			)
			(min_thickness 0.25)
			(keepout
				(tracks not_allowed)
				(vias allowed)
				(pads allowed)
				(copperpour not_allowed)
				(footprints allowed)
			)
			(placement
				(enabled no)
				(sheetname "")
			)
			(fill
				(thermal_gap 0.5)
				(thermal_bridge_width 0.5)
				(island_removal_mode 0)
			)
			(polygon
				(pts
					(xy 383.4384 -158.01594) (xy 383.4384 -158.52394) (xy 383.8194 -158.52394) (xy 383.8194 -158.01594)
				)
			)
		)
		(zone
			(layer "B.Cu")
			(hatch none 0.5)
			(connect_pads
				(clearance 0)
			)
			(min_thickness 0.25)
			(keepout
				(tracks allowed)
				(vias not_allowed)
				(pads allowed)
				(copperpour not_allowed)
				(footprints allowed)
			)
			(placement
				(enabled no)
				(sheetname "")
			)
			(fill
				(thermal_gap 0.5)
				(thermal_bridge_width 0.5)
				(island_removal_mode 0)
			)
			(polygon
				(pts
					(xy 383.8194 -158.01594) (xy 383.8194 -158.52394) (xy 383.4384 -158.52394) (xy 383.4384 -158.01594)
				)
			)
		)
	)
	(footprint ""
		(layer "B.Cu")
		(at 400.409156 -30.806898)
		(property "Reference" "C25W71"
			(at 0.8382 -0.67818 0)
			(unlocked yes)
			(layer "B.SilkS")
			(effects
				(font
					(size 0.4064 0.254)
					(thickness 0.1524)
				)
				(justify left mirror)
			)
		)
		(property "Value" ""
			(at 0 0 0)
			(layer "B.Fab")
			(effects
				(font
					(size 1.27 1.27)
				)
				(justify mirror)
			)
		)
		(duplicate_pad_numbers_are_jumpers no)
		(fp_poly
			(pts
				(xy -0.3048 -0.1016) (xy -0.3048 0.9906) (xy 0.3048 0.9906) (xy 0.3048 -0.1016)
			)
			(stroke
				(width 0)
				(type default)
			)
			(fill no)
			(layer "B.CrtYd")
		)
		(fp_line
			(start -0.3048 -0.1016)
			(end 0.3048 -0.1016)
			(stroke
				(width 0.1)
				(type default)
			)
			(layer "B.Fab")
		)
		(fp_line
			(start -0.3048 0.9906)
			(end -0.3048 -0.1016)
			(stroke
				(width 0.1)
				(type default)
			)
			(layer "B.Fab")
		)
		(fp_line
			(start 0.3048 -0.1016)
			(end 0.3048 0.9906)
			(stroke
				(width 0.1)
				(type default)
			)
			(layer "B.Fab")
		)
		(fp_line
			(start 0.3048 0.9906)
			(end -0.3048 0.9906)
			(stroke
				(width 0.1)
				(type default)
			)
			(layer "B.Fab")
		)
		(pad "1" smd rect
			(at 0 0 180)
			(size 0.508 0.508)
			(layers "B.Cu" "B.Mask" "B.Paste")
			(net "P3V3_USB2A_ALG")
		)
		(pad "2" smd rect
			(at 0 0.889 180)
			(size 0.508 0.508)
			(layers "B.Cu" "B.Mask" "B.Paste")
			(net "GND")
		)
		(zone
			(layer "B.Cu")
			(hatch none 0.5)
			(connect_pads
				(clearance 0)
			)
			(min_thickness 0.25)
			(keepout
				(tracks allowed)
				(vias not_allowed)
				(pads allowed)
				(copperpour not_allowed)
				(footprints allowed)
			)
			(placement
				(enabled no)
				(sheetname "")
			)
			(fill
				(thermal_gap 0.5)
				(thermal_bridge_width 0.5)
				(island_removal_mode 0)
			)
			(polygon
				(pts
					(xy 400.663156 -30.552898) (xy 400.155156 -30.552898) (xy 400.155156 -30.171898) (xy 400.663156 -30.171898)
				)
			)
		)
		(zone
			(layer "B.Cu")
			(hatch none 0.5)
			(connect_pads
				(clearance 0)
			)
			(min_thickness 0.25)
			(keepout
				(tracks not_allowed)
				(vias allowed)
				(pads allowed)
				(copperpour not_allowed)
				(footprints allowed)
			)
			(placement
				(enabled no)
				(sheetname "")
			)
			(fill
				(thermal_gap 0.5)
				(thermal_bridge_width 0.5)
				(island_removal_mode 0)
			)
			(polygon
				(pts
					(xy 400.663156 -30.171898) (xy 400.155156 -30.171898) (xy 400.155156 -30.552898) (xy 400.663156 -30.552898)
				)
			)
		)
	)
)
